(kicad_pcb
	(version 20260206)
	(generator "pcbnew")
	(generator_version "10.0")
	(general
		(thickness 1.6)
		(legacy_teardrops no)
	)
	(paper "A4")
	(title_block
		(title "peb — Lightning_PEB_BRD.brd")
		(comment 1 "Lightning (Wiwynn / Facebook NVMe JBOF) / footprints 433-440 of 2563")
	)
	(layers
		(0 "F.Cu" signal "TOP")
		(4 "In1.Cu" signal "L2GND")
		(6 "In2.Cu" signal "L3")
		(8 "In3.Cu" signal "L4VCC")
		(10 "In4.Cu" signal "L5VCC")
		(12 "In5.Cu" signal "L6")
		(14 "In6.Cu" signal "L7GND")
		(2 "B.Cu" signal "BOTTOM")
		(9 "F.Adhes" user "F.Adhesive")
		(11 "B.Adhes" user "B.Adhesive")
		(13 "F.Paste" user "Package Geometry/Pastemask Top")
		(15 "B.Paste" user "Package Geometry/Pastemask Bottom")
		(5 "F.SilkS" user "Ref Des/Silkscreen Top")
		(7 "B.SilkS" user "Ref Des/Silkscreen Bottom")
		(1 "F.Mask" user "Board Geometry/Soldermask Top")
		(3 "B.Mask" user "Board Geometry/Soldermask Bottom")
		(17 "Dwgs.User" user "User.Drawings")
		(19 "Cmts.User" user "User.Comments")
		(21 "Eco1.User" user "User.Eco1")
		(23 "Eco2.User" user "User.Eco2")
		(25 "Edge.Cuts" user "Board Geometry/Outline")
		(27 "Margin" user)
		(31 "F.CrtYd" user "Package Geometry/Place Bound Top")
		(29 "B.CrtYd" user "Package Geometry/Place Bound Bottom")
		(35 "F.Fab" user "Ref Des/Assembly Top")
		(33 "B.Fab" user "Ref Des/Assembly Bottom")
	)
	(footprint ""
		(layer "F.Cu")
		(at 34.798 -116.713)
		(property "Reference" "R23"
			(at 0 0 0)
			(layer "F.SilkS")
			(hide yes)
			(effects
				(font
					(size 1.27 1.27)
				)
			)
		)
		(property "Value" "10KR2F-2-GP"
			(at 0.064008 -3.993896 0)
			(unlocked yes)
			(layer "F.Fab")
			(hide yes)
			(effects
				(font
					(size 1.016 1.016)
					(thickness 0.1524)
				)
			)
		)
		(property "Device Type" "R402H16"
			(at 0.064008 -5.517896 0)
			(unlocked yes)
			(layer "F.Fab")
			(hide yes)
			(effects
				(font
					(size 1.016 1.016)
					(thickness 0.1524)
				)
			)
		)
		(duplicate_pad_numbers_are_jumpers no)
		(fp_line
			(start -0.508 -0.9398)
			(end -0.508 0.9398)
			(stroke
				(width 0.1524)
				(type default)
			)
			(layer "F.SilkS")
		)
		(fp_line
			(start 0.508 -0.9398)
			(end -0.508 -0.9398)
			(stroke
				(width 0.1524)
				(type default)
			)
			(layer "F.SilkS")
		)
		(fp_rect
			(start -0.508 0.9398)
			(end 0.508 -0.9398)
			(stroke
				(width 0)
				(type default)
			)
			(fill no)
			(layer "F.CrtYd")
		)
		(fp_rect
			(start -0.508 0.9398)
			(end 0.508 -0.9398)
			(stroke
				(width 0)
				(type default)
			)
			(fill no)
			(layer "F.Fab")
		)
		(pad "1" smd custom
			(at 0 -0.4445)
			(size 0.1397 0.1397)
			(layers "F.Cu" "F.Mask" "F.Paste")
			(net "PMC_PLX_BOARD")
			(options
				(clearance outline)
				(anchor circle)
			)
			(primitives
				(gr_poly
					(pts
						(arc
							(start -0.1778 -0.2794)
							(mid -0.249642 -0.249642)
							(end -0.2794 -0.1778)
						)
						(arc
							(start -0.2794 0.1778)
							(mid -0.249642 0.249642)
							(end -0.1778 0.2794)
						)
						(arc
							(start 0.1778 0.2794)
							(mid 0.249642 0.249642)
							(end 0.2794 0.1778)
						)
						(arc
							(start 0.2794 -0.1778)
							(mid 0.249642 -0.249642)
							(end 0.1778 -0.2794)
						)
					)
					(width 0)
					(fill yes)
				)
			)
		)
		(pad "2" smd custom
			(at 0 0.4445)
			(size 0.1397 0.1397)
			(layers "F.Cu" "F.Mask" "F.Paste")
			(net "P3V3_STBY")
			(options
				(clearance outline)
				(anchor circle)
			)
			(primitives
				(gr_poly
					(pts
						(arc
							(start -0.1778 -0.2794)
							(mid -0.249642 -0.249642)
							(end -0.2794 -0.1778)
						)
						(arc
							(start -0.2794 0.1778)
							(mid -0.249642 0.249642)
							(end -0.1778 0.2794)
						)
						(arc
							(start 0.1778 0.2794)
							(mid 0.249642 0.249642)
							(end 0.2794 0.1778)
						)
						(arc
							(start 0.2794 -0.1778)
							(mid 0.249642 -0.249642)
							(end 0.1778 -0.2794)
						)
					)
					(width 0)
					(fill yes)
				)
			)
		)
	)
	(footprint ""
		(layer "F.Cu")
		(at 155.65882 -86.0171 180)
		(property "Reference" "L10"
			(at 0 0 180)
			(layer "F.SilkS")
			(hide yes)
			(effects
				(font
					(size 1.27 1.27)
				)
			)
		)
		(property "Value" "BLM18SG121TN1D-GP"
			(at 0.0254 -2.7686 180)
			(unlocked yes)
			(layer "F.Fab")
			(hide yes)
			(effects
				(font
					(size 1.016 1.016)
					(thickness 0.1524)
				)
			)
		)
		(property "Device Type" "L603H26"
			(at 0.0254 -4.2926 180)
			(unlocked yes)
			(layer "F.Fab")
			(hide yes)
			(effects
				(font
					(size 1.016 1.016)
					(thickness 0.1524)
				)
			)
		)
		(duplicate_pad_numbers_are_jumpers no)
		(fp_line
			(start 0.254 0)
			(end -0.254 0)
			(stroke
				(width 0.2032)
				(type default)
			)
			(layer "F.SilkS")
		)
		(fp_rect
			(start -0.5842 1.3335)
			(end 0.5842 -1.3335)
			(stroke
				(width 0)
				(type default)
			)
			(fill no)
			(layer "F.CrtYd")
		)
		(fp_rect
			(start -0.5842 1.3335)
			(end 0.5842 -1.3335)
			(stroke
				(width 0)
				(type default)
			)
			(fill no)
			(layer "F.Fab")
		)
		(pad "1" smd custom
			(at 0 -0.762 180)
			(size 0.2159 0.2159)
			(layers "F.Cu" "F.Mask" "F.Paste")
			(net "P1V8_STBY")
			(options
				(clearance outline)
				(anchor circle)
			)
			(primitives
				(gr_poly
					(pts
						(arc
							(start -0.3302 -0.4318)
							(mid -0.402042 -0.402042)
							(end -0.4318 -0.3302)
						)
						(arc
							(start -0.4318 0.3302)
							(mid -0.402042 0.402042)
							(end -0.3302 0.4318)
						)
						(arc
							(start 0.3302 0.4318)
							(mid 0.402042 0.402042)
							(end 0.4318 0.3302)
						)
						(arc
							(start 0.4318 -0.3302)
							(mid 0.402042 -0.402042)
							(end 0.3302 -0.4318)
						)
					)
					(width 0)
					(fill yes)
				)
			)
		)
		(pad "2" smd custom
			(at 0 0.762 180)
			(size 0.2159 0.2159)
			(layers "F.Cu" "F.Mask" "F.Paste")
			(net "P1V8_CLKGEN")
			(options
				(clearance outline)
				(anchor circle)
			)
			(primitives
				(gr_poly
					(pts
						(arc
							(start -0.3302 -0.4318)
							(mid -0.402042 -0.402042)
							(end -0.4318 -0.3302)
						)
						(arc
							(start -0.4318 0.3302)
							(mid -0.402042 0.402042)
							(end -0.3302 0.4318)
						)
						(arc
							(start 0.3302 0.4318)
							(mid 0.402042 0.402042)
							(end 0.4318 0.3302)
						)
						(arc
							(start 0.4318 -0.3302)
							(mid 0.402042 -0.402042)
							(end 0.3302 -0.4318)
						)
					)
					(width 0)
					(fill yes)
				)
			)
		)
	)
	(footprint ""
		(layer "F.Cu")
		(at 74.742548 -120.0912 -90)
		(property "Reference" "U53"
			(at 0 0 270)
			(layer "F.SilkS")
			(hide yes)
			(effects
				(font
					(size 1.27 1.27)
				)
			)
		)
		(property "Value" "SN74LVC1G07DCKRG4-2-GP"
			(at -2.3368 -8.6868 270)
			(unlocked yes)
			(layer "F.Fab")
			(hide yes)
			(effects
				(font
					(size 1.016 1.016)
					(thickness 0.1524)
				)
			)
		)
		(property "Device Type" "SC70-5H44"
			(at -2.3114 -10.414 270)
			(unlocked yes)
			(layer "F.Fab")
			(hide yes)
			(effects
				(font
					(size 1.016 1.016)
					(thickness 0.1524)
				)
			)
		)
		(duplicate_pad_numbers_are_jumpers no)
		(fp_line
			(start -1.27 1.7018)
			(end -1.27 -1.7018)
			(stroke
				(width 0.1524)
				(type default)
			)
			(layer "F.SilkS")
		)
		(fp_line
			(start 1.27 1.7018)
			(end -1.27 1.7018)
			(stroke
				(width 0.1524)
				(type default)
			)
			(layer "F.SilkS")
		)
		(fp_line
			(start -1.27 -1.7018)
			(end 1.27 -1.7018)
			(stroke
				(width 0.1524)
				(type default)
			)
			(layer "F.SilkS")
		)
		(fp_line
			(start 1.27 -1.7018)
			(end 1.27 1.7018)
			(stroke
				(width 0.1524)
				(type default)
			)
			(layer "F.SilkS")
		)
		(fp_line
			(start 0.6604 -1.8034)
			(end 1.3843 -1.8034)
			(stroke
				(width 0.3302)
				(type default)
			)
			(layer "F.SilkS")
		)
		(fp_line
			(start 1.3843 -1.8034)
			(end 1.3843 -1.1176)
			(stroke
				(width 0.3302)
				(type default)
			)
			(layer "F.SilkS")
		)
		(fp_rect
			(start -1.524 1.9558)
			(end 1.524 -1.9558)
			(stroke
				(width 0)
				(type default)
			)
			(fill no)
			(layer "F.CrtYd")
		)
		(fp_poly
			(pts
				(xy -1.524 -1.9558) (xy 1.524 -1.9558) (xy 1.524 1.9558) (xy -1.524 1.9558)
			)
			(stroke
				(width 0)
				(type default)
			)
			(fill no)
			(layer "F.Fab")
		)
		(pad "1" smd rect
			(at 0.65024 -0.8255 270)
			(size 0.4064 1.2192)
			(layers "F.Cu" "F.Mask" "F.Paste")
			(net "Net_112")
		)
		(pad "2" smd rect
			(at 0 -0.8255 270)
			(size 0.4064 1.2192)
			(layers "F.Cu" "F.Mask" "F.Paste")
			(net "MBP_UART_RX")
		)
		(pad "3" smd rect
			(at -0.65024 -0.8255 270)
			(size 0.4064 1.2192)
			(layers "F.Cu" "F.Mask" "F.Paste")
			(net "GND")
		)
		(pad "4" smd rect
			(at -0.65024 0.8255 270)
			(size 0.4064 1.2192)
			(layers "F.Cu" "F.Mask" "F.Paste")
			(net "BMC_RXD5_R")
		)
		(pad "5" smd rect
			(at 0.65024 0.8255 270)
			(size 0.4064 1.2192)
			(layers "F.Cu" "F.Mask" "F.Paste")
			(net "P3V3_STBY")
		)
	)
	(footprint ""
		(layer "F.Cu")
		(at 130.024124 -196.443092)
		(property "Reference" "R7922"
			(at 0 0 0)
			(layer "F.SilkS")
			(hide yes)
			(effects
				(font
					(size 1.27 1.27)
				)
			)
		)
		(property "Value" "0R2J-2-GP"
			(at 0.064008 -3.993896 0)
			(unlocked yes)
			(layer "F.Fab")
			(hide yes)
			(effects
				(font
					(size 1.016 1.016)
					(thickness 0.1524)
				)
			)
		)
		(property "Device Type" "R402H16"
			(at 0.064008 -5.517896 0)
			(unlocked yes)
			(layer "F.Fab")
			(hide yes)
			(effects
				(font
					(size 1.016 1.016)
					(thickness 0.1524)
				)
			)
		)
		(duplicate_pad_numbers_are_jumpers no)
		(fp_line
			(start -0.508 -0.9398)
			(end -0.508 0.9398)
			(stroke
				(width 0.1524)
				(type default)
			)
			(layer "F.SilkS")
		)
		(fp_line
			(start 0.508 -0.9398)
			(end -0.508 -0.9398)
			(stroke
				(width 0.1524)
				(type default)
			)
			(layer "F.SilkS")
		)
		(fp_rect
			(start -0.508 0.9398)
			(end 0.508 -0.9398)
			(stroke
				(width 0)
				(type default)
			)
			(fill no)
			(layer "F.CrtYd")
		)
		(fp_rect
			(start -0.508 0.9398)
			(end 0.508 -0.9398)
			(stroke
				(width 0)
				(type default)
			)
			(fill no)
			(layer "F.Fab")
		)
		(pad "1" smd custom
			(at 0 -0.4445)
			(size 0.1397 0.1397)
			(layers "F.Cu" "F.Mask" "F.Paste")
			(net "SSD_PRSNT#2")
			(options
				(clearance outline)
				(anchor circle)
			)
			(primitives
				(gr_poly
					(pts
						(arc
							(start -0.1778 -0.2794)
							(mid -0.249642 -0.249642)
							(end -0.2794 -0.1778)
						)
						(arc
							(start -0.2794 0.1778)
							(mid -0.249642 0.249642)
							(end -0.1778 0.2794)
						)
						(arc
							(start 0.1778 0.2794)
							(mid 0.249642 0.249642)
							(end 0.2794 0.1778)
						)
						(arc
							(start 0.2794 -0.1778)
							(mid 0.249642 -0.249642)
							(end 0.1778 -0.2794)
						)
					)
					(width 0)
					(fill yes)
				)
			)
		)
		(pad "2" smd custom
			(at 0 0.4445)
			(size 0.1397 0.1397)
			(layers "F.Cu" "F.Mask" "F.Paste")
			(net "SSD_PRSNT#2_R")
			(options
				(clearance outline)
				(anchor circle)
			)
			(primitives
				(gr_poly
					(pts
						(arc
							(start -0.1778 -0.2794)
							(mid -0.249642 -0.249642)
							(end -0.2794 -0.1778)
						)
						(arc
							(start -0.2794 0.1778)
							(mid -0.249642 0.249642)
							(end -0.1778 0.2794)
						)
						(arc
							(start 0.1778 0.2794)
							(mid 0.249642 0.249642)
							(end 0.2794 0.1778)
						)
						(arc
							(start 0.2794 -0.1778)
							(mid 0.249642 -0.249642)
							(end 0.1778 -0.2794)
						)
					)
					(width 0)
					(fill yes)
				)
			)
		)
	)
	(footprint ""
		(layer "F.Cu")
		(at 118.59387 -30.639512 180)
		(property "Reference" "R2961"
			(at 0 0 180)
			(layer "F.SilkS")
			(hide yes)
			(effects
				(font
					(size 1.27 1.27)
				)
			)
		)
		(property "Value" "0R2J-2-GP"
			(at 0.064008 -3.993896 180)
			(unlocked yes)
			(layer "F.Fab")
			(hide yes)
			(effects
				(font
					(size 1.016 1.016)
					(thickness 0.1524)
				)
			)
		)
		(property "Device Type" "R402H16"
			(at 0.064008 -5.517896 180)
			(unlocked yes)
			(layer "F.Fab")
			(hide yes)
			(effects
				(font
					(size 1.016 1.016)
					(thickness 0.1524)
				)
			)
		)
		(duplicate_pad_numbers_are_jumpers no)
		(fp_line
			(start 0.508 -0.9398)
			(end -0.508 -0.9398)
			(stroke
				(width 0.1524)
				(type default)
			)
			(layer "F.SilkS")
		)
		(fp_line
			(start -0.508 -0.9398)
			(end -0.508 0.9398)
			(stroke
				(width 0.1524)
				(type default)
			)
			(layer "F.SilkS")
		)
		(fp_rect
			(start -0.508 0.9398)
			(end 0.508 -0.9398)
			(stroke
				(width 0)
				(type default)
			)
			(fill no)
			(layer "F.CrtYd")
		)
		(fp_rect
			(start -0.508 0.9398)
			(end 0.508 -0.9398)
			(stroke
				(width 0)
				(type default)
			)
			(fill no)
			(layer "F.Fab")
		)
		(pad "1" smd custom
			(at 0 -0.4445 180)
			(size 0.1397 0.1397)
			(layers "F.Cu" "F.Mask" "F.Paste")
			(net "U54_SCL")
			(options
				(clearance outline)
				(anchor circle)
			)
			(primitives
				(gr_poly
					(pts
						(arc
							(start -0.1778 -0.2794)
							(mid -0.249642 -0.249642)
							(end -0.2794 -0.1778)
						)
						(arc
							(start -0.2794 0.1778)
							(mid -0.249642 0.249642)
							(end -0.1778 0.2794)
						)
						(arc
							(start 0.1778 0.2794)
							(mid 0.249642 0.249642)
							(end 0.2794 0.1778)
						)
						(arc
							(start 0.2794 -0.1778)
							(mid 0.249642 -0.249642)
							(end 0.1778 -0.2794)
						)
					)
					(width 0)
					(fill yes)
				)
			)
		)
		(pad "2" smd custom
			(at 0 0.4445 180)
			(size 0.1397 0.1397)
			(layers "F.Cu" "F.Mask" "F.Paste")
			(net "BMC_I2C1_MINI1_SCL_S")
			(options
				(clearance outline)
				(anchor circle)
			)
			(primitives
				(gr_poly
					(pts
						(arc
							(start -0.1778 -0.2794)
							(mid -0.249642 -0.249642)
							(end -0.2794 -0.1778)
						)
						(arc
							(start -0.2794 0.1778)
							(mid -0.249642 0.249642)
							(end -0.1778 0.2794)
						)
						(arc
							(start 0.1778 0.2794)
							(mid 0.249642 0.249642)
							(end 0.2794 0.1778)
						)
						(arc
							(start 0.2794 -0.1778)
							(mid 0.249642 -0.249642)
							(end 0.1778 -0.2794)
						)
					)
					(width 0)
					(fill yes)
				)
			)
		)
	)
	(footprint ""
		(layer "F.Cu")
		(at 317.418466 -33.42513)
		(property "Reference" "R377"
			(at 0 0 0)
			(layer "F.SilkS")
			(hide yes)
			(effects
				(font
					(size 1.27 1.27)
				)
			)
		)
		(property "Value" "0R2J-2-GP"
			(at 0.064008 -3.993896 0)
			(unlocked yes)
			(layer "F.Fab")
			(hide yes)
			(effects
				(font
					(size 1.016 1.016)
					(thickness 0.1524)
				)
			)
		)
		(property "Device Type" "R402H16"
			(at 0.064008 -5.517896 0)
			(unlocked yes)
			(layer "F.Fab")
			(hide yes)
			(effects
				(font
					(size 1.016 1.016)
					(thickness 0.1524)
				)
			)
		)
		(duplicate_pad_numbers_are_jumpers no)
		(fp_line
			(start -0.508 -0.9398)
			(end -0.508 0.9398)
			(stroke
				(width 0.1524)
				(type default)
			)
			(layer "F.SilkS")
		)
		(fp_line
			(start 0.508 -0.9398)
			(end -0.508 -0.9398)
			(stroke
				(width 0.1524)
				(type default)
			)
			(layer "F.SilkS")
		)
		(fp_rect
			(start -0.508 0.9398)
			(end 0.508 -0.9398)
			(stroke
				(width 0)
				(type default)
			)
			(fill no)
			(layer "F.CrtYd")
		)
		(fp_rect
			(start -0.508 0.9398)
			(end 0.508 -0.9398)
			(stroke
				(width 0)
				(type default)
			)
			(fill no)
			(layer "F.Fab")
		)
		(pad "1" smd custom
			(at 0 -0.4445)
			(size 0.1397 0.1397)
			(layers "F.Cu" "F.Mask" "F.Paste")
			(net "CLK_P_8_R")
			(options
				(clearance outline)
				(anchor circle)
			)
			(primitives
				(gr_poly
					(pts
						(arc
							(start -0.1778 -0.2794)
							(mid -0.249642 -0.249642)
							(end -0.2794 -0.1778)
						)
						(arc
							(start -0.2794 0.1778)
							(mid -0.249642 0.249642)
							(end -0.1778 0.2794)
						)
						(arc
							(start 0.1778 0.2794)
							(mid 0.249642 0.249642)
							(end 0.2794 0.1778)
						)
						(arc
							(start 0.2794 -0.1778)
							(mid 0.249642 -0.249642)
							(end 0.1778 -0.2794)
						)
					)
					(width 0)
					(fill yes)
				)
			)
		)
		(pad "2" smd custom
			(at 0 0.4445)
			(size 0.1397 0.1397)
			(layers "F.Cu" "F.Mask" "F.Paste")
			(net "CLK_P_8")
			(options
				(clearance outline)
				(anchor circle)
			)
			(primitives
				(gr_poly
					(pts
						(arc
							(start -0.1778 -0.2794)
							(mid -0.249642 -0.249642)
							(end -0.2794 -0.1778)
						)
						(arc
							(start -0.2794 0.1778)
							(mid -0.249642 0.249642)
							(end -0.1778 0.2794)
						)
						(arc
							(start 0.1778 0.2794)
							(mid 0.249642 0.249642)
							(end 0.2794 0.1778)
						)
						(arc
							(start 0.2794 -0.1778)
							(mid 0.249642 -0.249642)
							(end 0.1778 -0.2794)
						)
					)
					(width 0)
					(fill yes)
				)
			)
		)
	)
	(footprint ""
		(layer "F.Cu")
		(at 321.437 -99.568)
		(property "Reference" "R7998"
			(at 0 0 0)
			(layer "F.SilkS")
			(hide yes)
			(effects
				(font
					(size 1.27 1.27)
				)
			)
		)
		(property "Value" "330R2J-3-GP"
			(at 0.064008 -3.993896 0)
			(unlocked yes)
			(layer "F.Fab")
			(hide yes)
			(effects
				(font
					(size 1.016 1.016)
					(thickness 0.1524)
				)
			)
		)
		(property "Device Type" "R402H16"
			(at 0.064008 -5.517896 0)
			(unlocked yes)
			(layer "F.Fab")
			(hide yes)
			(effects
				(font
					(size 1.016 1.016)
					(thickness 0.1524)
				)
			)
		)
		(duplicate_pad_numbers_are_jumpers no)
		(fp_line
			(start -0.508 -0.9398)
			(end -0.508 0.9398)
			(stroke
				(width 0.1524)
				(type default)
			)
			(layer "F.SilkS")
		)
		(fp_line
			(start 0.508 -0.9398)
			(end -0.508 -0.9398)
			(stroke
				(width 0.1524)
				(type default)
			)
			(layer "F.SilkS")
		)
		(fp_rect
			(start -0.508 0.9398)
			(end 0.508 -0.9398)
			(stroke
				(width 0)
				(type default)
			)
			(fill no)
			(layer "F.CrtYd")
		)
		(fp_rect
			(start -0.508 0.9398)
			(end 0.508 -0.9398)
			(stroke
				(width 0)
				(type default)
			)
			(fill no)
			(layer "F.Fab")
		)
		(pad "1" smd custom
			(at 0 -0.4445)
			(size 0.1397 0.1397)
			(layers "F.Cu" "F.Mask" "F.Paste")
			(net "TWI_SCL3")
			(options
				(clearance outline)
				(anchor circle)
			)
			(primitives
				(gr_poly
					(pts
						(arc
							(start -0.1778 -0.2794)
							(mid -0.249642 -0.249642)
							(end -0.2794 -0.1778)
						)
						(arc
							(start -0.2794 0.1778)
							(mid -0.249642 0.249642)
							(end -0.1778 0.2794)
						)
						(arc
							(start 0.1778 0.2794)
							(mid 0.249642 0.249642)
							(end 0.2794 0.1778)
						)
						(arc
							(start 0.2794 -0.1778)
							(mid 0.249642 -0.249642)
							(end 0.1778 -0.2794)
						)
					)
					(width 0)
					(fill yes)
				)
			)
		)
		(pad "2" smd custom
			(at 0 0.4445)
			(size 0.1397 0.1397)
			(layers "F.Cu" "F.Mask" "F.Paste")
			(net "IOEXP_TWI_SCL3")
			(options
				(clearance outline)
				(anchor circle)
			)
			(primitives
				(gr_poly
					(pts
						(arc
							(start -0.1778 -0.2794)
							(mid -0.249642 -0.249642)
							(end -0.2794 -0.1778)
						)
						(arc
							(start -0.2794 0.1778)
							(mid -0.249642 0.249642)
							(end -0.1778 0.2794)
						)
						(arc
							(start 0.1778 0.2794)
							(mid 0.249642 0.249642)
							(end 0.2794 0.1778)
						)
						(arc
							(start 0.2794 -0.1778)
							(mid 0.249642 -0.249642)
							(end 0.1778 -0.2794)
						)
					)
					(width 0)
					(fill yes)
				)
			)
		)
	)
	(footprint ""
		(layer "F.Cu")
		(at 178.1048 -65.405 180)
		(property "Reference" "PG15"
			(at 0 0 180)
			(layer "F.SilkS")
			(hide yes)
			(effects
				(font
					(size 1.27 1.27)
				)
			)
		)
		(property "Value" "GAP-CLOSE-PWR-3-GP"
			(at 0.0254 -6.5786 180)
			(unlocked yes)
			(layer "F.Fab")
			(hide yes)
			(effects
				(font
					(size 1.016 1.016)
					(thickness 0.1524)
				)
			)
		)
		(property "Device Type" "GAP-CLOSE-PWR-3"
			(at 0.0254 -8.255 180)
			(unlocked yes)
			(layer "F.Fab")
			(hide yes)
			(effects
				(font
					(size 1.016 1.016)
					(thickness 0.1524)
				)
			)
		)
		(duplicate_pad_numbers_are_jumpers no)
		(fp_rect
			(start -0.7112 0.4572)
			(end 0.7112 -0.4572)
			(stroke
				(width 0)
				(type default)
			)
			(fill no)
			(layer "F.CrtYd")
		)
		(fp_poly
			(pts
				(xy -0.7112 -0.4572) (xy 0.7112 -0.4572) (xy 0.7112 0.4572) (xy -0.7112 0.4572)
			)
			(stroke
				(width 0)
				(type default)
			)
			(fill no)
			(layer "F.Fab")
		)
		(pad "1" smd rect
			(at -0.3048 0 180)
			(size 0.6604 0.762)
			(layers "F.Cu" "F.Mask" "F.Paste")
			(net "DUT_AVD_PCIE")
		)
		(pad "2" smd rect
			(at 0.3048 0 180)
			(size 0.6604 0.762)
			(layers "F.Cu" "F.Mask" "F.Paste")
			(net "P0V9")
		)
	)
)
